#ISCELL
  pure_quanta quanta_title_block_c *
  *
#CELL
  pure_quanta genoa_sp5 *
  page22_i207
#CELL
  pure_quanta genoa_sp5 *
  page22_i208
#ISCELL
  standard offpage *
  page22_i243
#ISCELL
  standard offpage *
  page22_i244
#ISCELL
  mstr_standard tap *
  page22_i245
#ISCELL
  mstr_standard tap *
  page22_i246
#ISCELL
  mstr_standard tap *
  page22_i247
#ISCELL
  standard tap *
  page22_i248
#ISCELL
  standard tap *
  page22_i249
#ISCELL
  mstr_standard tap *
  page22_i250
#ISCELL
  standard tap *
  page22_i251
#ISCELL
  standard tap *
  page22_i252
#ISCELL
  standard tap *
  page22_i253
#ISCELL
  standard tap *
  page22_i254
#ISCELL
  standard tap *
  page22_i255
#ISCELL
  standard tap *
  page22_i256
#ISCELL
  standard tap *
  page22_i257
#ISCELL
  standard tap *
  page22_i258
#ISCELL
  standard tap *
  page22_i259
#ISCELL
  standard tap *
  page22_i260
#ISCELL
  standard tap *
  page22_i261
#ISCELL
  standard tap *
  page22_i262
#ISCELL
  standard tap *
  page22_i263
#ISCELL
  standard tap *
  page22_i264
#ISCELL
  standard tap *
  page22_i265
#ISCELL
  standard tap *
  page22_i266
#ISCELL
  standard tap *
  page22_i267
#ISCELL
  standard tap *
  page22_i268
#ISCELL
  standard tap *
  page22_i269
#ISCELL
  standard tap *
  page22_i270
#ISCELL
  standard tap *
  page22_i271
#ISCELL
  standard tap *
  page22_i272
#ISCELL
  standard tap *
  page22_i273
#ISCELL
  standard tap *
  page22_i274
#ISCELL
  standard tap *
  page22_i275
#ISCELL
  standard tap *
  page22_i276
#ISCELL
  mstr_standard tap *
  page22_i277
#ISCELL
  mstr_standard tap *
  page22_i278
#ISCELL
  mstr_standard tap *
  page22_i279
#ISCELL
  mstr_standard tap *
  page22_i280
#ISCELL
  mstr_standard tap *
  page22_i281
#ISCELL
  standard tap *
  page22_i282
#ISCELL
  standard tap *
  page22_i283
#ISCELL
  standard tap *
  page22_i284
#ISCELL
  standard tap *
  page22_i285
#ISCELL
  standard tap *
  page22_i286
#ISCELL
  standard tap *
  page22_i287
#ISCELL
  standard tap *
  page22_i288
#ISCELL
  standard tap *
  page22_i289
#ISCELL
  standard tap *
  page22_i290
#ISCELL
  standard tap *
  page22_i291
#ISCELL
  standard tap *
  page22_i292
#ISCELL
  standard tap *
  page22_i293
#ISCELL
  standard tap *
  page22_i294
#ISCELL
  standard tap *
  page22_i295
#ISCELL
  standard tap *
  page22_i296
#ISCELL
  standard tap *
  page22_i297
#ISCELL
  standard tap *
  page22_i298
#ISCELL
  standard tap *
  page22_i299
#ISCELL
  standard tap *
  page22_i300
#ISCELL
  standard tap *
  page22_i301
#ISCELL
  standard tap *
  page22_i302
#ISCELL
  standard tap *
  page22_i303
#ISCELL
  standard tap *
  page22_i304
#ISCELL
  standard tap *
  page22_i305
#ISCELL
  standard tap *
  page22_i306
#ISCELL
  standard tap *
  page22_i307
#ISCELL
  standard tap *
  page22_i308
#ISCELL
  standard offpage *
  page22_i309
#ISCELL
  standard offpage *
  page22_i310
#ISCELL
  standard offpage *
  page22_i311
#ISCELL
  standard offpage *
  page22_i312
#ISCELL
  mstr_standard tap *
  page22_i313
#ISCELL
  mstr_standard tap *
  page22_i314
#ISCELL
  mstr_standard tap *
  page22_i315
#ISCELL
  mstr_standard tap *
  page22_i316
#ISCELL
  standard tap *
  page22_i317
#ISCELL
  standard tap *
  page22_i318
#ISCELL
  standard tap *
  page22_i319
#ISCELL
  standard tap *
  page22_i320
#ISCELL
  standard tap *
  page22_i321
#ISCELL
  standard tap *
  page22_i322
#ISCELL
  standard tap *
  page22_i323
#ISCELL
  standard tap *
  page22_i324
#ISCELL
  standard tap *
  page22_i325
#ISCELL
  standard tap *
  page22_i326
#ISCELL
  standard tap *
  page22_i327
#ISCELL
  standard tap *
  page22_i328
#ISCELL
  standard tap *
  page22_i329
#ISCELL
  standard tap *
  page22_i330
#ISCELL
  standard tap *
  page22_i331
#ISCELL
  standard tap *
  page22_i332
#ISCELL
  standard tap *
  page22_i333
#ISCELL
  standard tap *
  page22_i334
#ISCELL
  standard tap *
  page22_i335
#ISCELL
  standard tap *
  page22_i336
#ISCELL
  standard tap *
  page22_i337
#ISCELL
  standard tap *
  page22_i338
#ISCELL
  standard tap *
  page22_i339
#ISCELL
  standard tap *
  page22_i340
#ISCELL
  standard tap *
  page22_i341
#ISCELL
  standard tap *
  page22_i342
#ISCELL
  standard tap *
  page22_i343
#ISCELL
  standard tap *
  page22_i344
#ISCELL
  mstr_standard tap *
  page22_i345
#ISCELL
  mstr_standard tap *
  page22_i346
#ISCELL
  mstr_standard tap *
  page22_i347
#ISCELL
  mstr_standard tap *
  page22_i348
#ISCELL
  standard tap *
  page22_i349
#ISCELL
  standard tap *
  page22_i350
#ISCELL
  mstr_standard tap *
  page22_i351
#ISCELL
  standard tap *
  page22_i352
#ISCELL
  standard tap *
  page22_i353
#ISCELL
  standard tap *
  page22_i354
#ISCELL
  standard tap *
  page22_i355
#ISCELL
  standard tap *
  page22_i356
#ISCELL
  standard tap *
  page22_i357
#ISCELL
  standard tap *
  page22_i358
#ISCELL
  standard tap *
  page22_i359
#ISCELL
  standard tap *
  page22_i360
#ISCELL
  standard tap *
  page22_i361
#ISCELL
  standard tap *
  page22_i362
#ISCELL
  standard tap *
  page22_i363
#ISCELL
  standard offpage *
  page22_i364
#ISCELL
  standard offpage *
  page22_i365
#ISCELL
  standard tap *
  page22_i366
#ISCELL
  standard tap *
  page22_i367
#ISCELL
  standard tap *
  page22_i368
#ISCELL
  standard tap *
  page22_i369
#ISCELL
  standard tap *
  page22_i370
#ISCELL
  standard tap *
  page22_i371
#ISCELL
  standard tap *
  page22_i372
#ISCELL
  standard tap *
  page22_i373
#ISCELL
  standard tap *
  page22_i374
#ISCELL
  standard tap *
  page22_i375
#ISCELL
  standard tap *
  page22_i376
#ISCELL
  standard tap *
  page22_i377
#ISCELL
  standard tap *
  page22_i378
